# SCM (Grand Teton) — schematic netlist excerpt (pin names and nets, part order shuffled) for the footprints in the layout excerpt that follows; sources: Cadence DE-HDL packaged netlist, KiCad conversion of 12092022_DA0F0TMDCD0_F0T_Management_Board_D_brd_V3_OCP.brd

U1  K4A8G165WCBCTD  K4A8G165WC-BCTD IC  pkg BGA96XB  page 20
  VDDQ0  = P1V2_AUX
  VSSQ0  = GND
  DQU0  = M_BMC_DDR4_DQ<8>
  DQSU_C  = M_BMC_DDR4_DQS1_N
  VSSQ1  = GND
  VDDQ1  = P1V2_AUX
  VPP0  = P2V5_AUX
  VSS0  = GND
  VDD0  = P1V2_AUX
  DQSU_T  = M_BMC_DDR4_DQS1_P
  DQU1  = M_BMC_DDR4_DQ<9>
  VDD1  = P1V2_AUX
  VDDQ2  = P1V2_AUX
  DQU4  = M_BMC_DDR4_DQ<12>
  DQU2  = M_BMC_DDR4_DQ<10>
  DQU3  = M_BMC_DDR4_DQ<11>
  DQU5  = M_BMC_DDR4_DQ<13>
  VSSQ2  = GND
  VDD2  = P1V2_AUX
  VSSQ3  = GND
  DQU6  = M_BMC_DDR4_DQ<14>
  DQU7  = M_BMC_DDR4_DQ<15>
  VSSQ4  = GND
  VDDQ3  = P1V2_AUX
  VSS1  = GND
  \dmu_n||dbiu_n\  = M_BMC_DDR4_MDM1
  VSSQ5  = GND
  \dml_n||dbil_n\  = M_BMC_DDR4_MDM0
  VSSQ6  = GND
  VSS2  = M_BMC_DDR4_ZQU
  VSSQ7  = GND
  VDDQ4  = P1V2_AUX
  DQSL_C  = M_BMC_DDR4_DQS0_N
  DQL1  = M_BMC_DDR4_DQ<1>
  VDDQ5  = P1V2_AUX
  ZQ  = PD_M_BMC_DDR4_ZQ
  VDDQ6  = P1V2_AUX
  DQL0  = M_BMC_DDR4_DQ<0>
  DQSL_T  = M_BMC_DDR4_DQS0_P
  VDD3  = P1V2_AUX
  VSS3  = GND
  VDDQ7  = P1V2_AUX
  VSSQ8  = GND
  DQL4  = M_BMC_DDR4_DQ<4>
  DQL2  = M_BMC_DDR4_DQ<2>
  DQL3  = M_BMC_DDR4_DQ<3>
  DQL5  = M_BMC_DDR4_DQ<5>
  VSSQ9  = GND
  VDD4  = P1V2_AUX
  VDDQ8  = P1V2_AUX
  DQL6  = M_BMC_DDR4_DQ<6>
  DQL7  = M_BMC_DDR4_DQ<7>
  VDDQ9  = P1V2_AUX
  VDD5  = P1V2_AUX
  VSS4  = GND
  CKE  = M_BMC_DDR4_MCKE
  ODT  = M_BMC_DDR4_MODT
  CK_T  = M_BMC_DDR4_MCLK_DP
  CK_C  = M_BMC_DDR4_MCLK_DN
  VSS5  = GND
  VDD6  = P1V2_AUX
  \we_n||a14\  = M_BMC_DDR4_MWE_N
  ACT_N  = M_BMC_DDR4_MACT_N
  CS_N  = M_BMC_DDR4_MCS_N
  RAS_N  = M_BMC_DDR4_MRAS_N
  VDD7  = P1V2_AUX
  VREFCA  = P0V6_DDR_VREF_AUX
  BG0  = M_BMC_DDR4_MBG0
  \a10||ap\  = M_BMC_DDR4_MA<10>
  \a12||bc_n\  = M_BMC_DDR4_MA<12>
  \cas_n||a15\  = M_BMC_DDR4_MCAS_N
  VSS6  = M_BMC_DDR4_BG1
  VSS7  = GND
  BA0  = M_BMC_DDR4_MBA0
  A4  = M_BMC_DDR4_MA<4>
  A3  = M_BMC_DDR4_MA<3>
  BA1  = M_BMC_DDR4_MBA1
  TEN  = PD_M_BMC_DDR4_TEN
  RESET_N  = M_BMC_DDR4_RST_N
  A6  = M_BMC_DDR4_MA<6>
  A0  = M_BMC_DDR4_MA<0>
  A1  = M_BMC_DDR4_MA<1>
  A5  = M_BMC_DDR4_MA<5>
  ALERT_N  = M_BMC_DDR4_ALERT_N
  VDD8  = P1V2_AUX
  A8  = M_BMC_DDR4_MA<8>
  A2  = M_BMC_DDR4_MA<2>
  A9  = M_BMC_DDR4_MA<9>
  A7  = M_BMC_DDR4_MA<7>
  VPP1  = P2V5_AUX
  VSS8  = GND
  A11  = M_BMC_DDR4_MA<11>
  PAR  = PD_M_BMC_DDR4_PAR
  NC1  = GND
  A13  = M_BMC_DDR4_MA<13>
  VDD9  = P1V2_AUX

(kicad_pcb
	(version 20260206)
	(generator "pcbnew")
	(generator_version "10.0")
	(general
		(thickness 1.6)
		(legacy_teardrops no)
	)
	(paper "A4")
	(title_block
		(title "12092022_DA0F0TMDCD0_F0T_Management_Board_D_brd_V3_OCP.brd")
		(comment 1 "Grand Teton / footprint 201 of 1440 (U1), pads 96-96 of 96")
	)
	(layers
		(0 "F.Cu" signal "TOP")
		(4 "In1.Cu" signal "GND")
		(6 "In2.Cu" signal "IN1")
		(8 "In3.Cu" signal "GND1")
		(10 "In4.Cu" signal "IN2")
		(12 "In5.Cu" signal "VCC")
		(14 "In6.Cu" signal "VCC1")
		(16 "In7.Cu" signal "IN3")
		(18 "In8.Cu" signal "GND2")
		(20 "In9.Cu" signal "IN4")
		(22 "In10.Cu" signal "GND3")
		(2 "B.Cu" signal "BOTTOM")
		(9 "F.Adhes" user "F.Adhesive")
		(11 "B.Adhes" user "B.Adhesive")
		(13 "F.Paste" user "Package Geometry/Pastemask Top")
		(15 "B.Paste" user "Package Geometry/Pastemask Bottom")
		(5 "F.SilkS" user "Ref Des/Silkscreen Top")
		(7 "B.SilkS" user "Ref Des/Silkscreen Bottom")
		(1 "F.Mask" user "Board Geometry/Soldermask Top")
		(3 "B.Mask" user "Board Geometry/Soldermask Bottom")
		(17 "Dwgs.User" user "User.Drawings")
		(19 "Cmts.User" user "User.Comments")
		(21 "Eco1.User" user "User.Eco1")
		(23 "Eco2.User" user "User.Eco2")
		(25 "Edge.Cuts" user "Board Geometry/Outline")
		(27 "Margin" user)
		(31 "F.CrtYd" user "Package Geometry/Place Bound Top")
		(29 "B.CrtYd" user "Package Geometry/Place Bound Bottom")
		(35 "F.Fab" user "Ref Des/Assembly Top")
		(33 "B.Fab" user "Ref Des/Assembly Bottom")
	)
	(footprint ""
		(layer "F.Cu")
		(at 76.252324 -47.907448)
		(property "Reference" "U1"
			(at -4.664456 -10.397744 0)
			(unlocked yes)
			(layer "F.SilkS")
			(effects
				(font
					(size 0.7874 0.5842)
					(thickness 0.1524)
				)
				(justify left)
			)
		)
		(property "Value" ""
			(at 0 0 0)
			(layer "F.Fab")
			(effects
				(font
					(size 1.27 1.27)
				)
			)
		)
		(duplicate_pad_numbers_are_jumpers no)
		(pad "T9" smd circle
			(at 3.199892 5.999988)
			(size 0.3683 0.3683)
			(layers "F.Cu" "F.Mask" "F.Paste")
			(net "P1V2_AUX")
		)
	)
)
